# T6G (Grand Teton) — schematic netlist excerpt (pin names and nets, part order shuffled) for the footprints in the layout excerpt that follows; sources: Cadence DE-HDL packaged netlist, KiCad conversion of 04192023_DAF0TMB3IC0_F0TG_MB_C_brd_V02_OCP.brd

C489  Q_CAP  10UF 6.3V 20% X6S  pkg C0402  page 356 : A = P0V9_CPU1_RT_2D ; B = GND
C424  Q_CAP  22UF 4V 20% X6S  pkg C0402  page 345 : A = P0V9_CPU1_RT2_2A ; B = GND
C191  Q_CAP  0.1UF 10V 10% X7S  pkg C0201  page 323 : A = P0V9_CPU1_RT0_2A_2D ; B = GND

(kicad_pcb
	(version 20260206)
	(generator "pcbnew")
	(generator_version "10.0")
	(general
		(thickness 1.6)
		(legacy_teardrops no)
	)
	(paper "A4")
	(title_block
		(title "04192023_DAF0TMB3IC0_F0TG_MB_C_brd_V02_OCP.brd")
		(comment 1 "Grand Teton / footprints 7214-7216 of 8354")
	)
	(layers
		(0 "F.Cu" signal "TOP")
		(4 "In1.Cu" signal "GND")
		(6 "In2.Cu" signal "IN1")
		(8 "In3.Cu" signal "GND1")
		(10 "In4.Cu" signal "IN2")
		(12 "In5.Cu" signal "GND2")
		(14 "In6.Cu" signal "IN3")
		(16 "In7.Cu" signal "GND3")
		(18 "In8.Cu" signal "VCC")
		(20 "In9.Cu" signal "VCC1")
		(22 "In10.Cu" signal "GND4")
		(24 "In11.Cu" signal "IN4")
		(26 "In12.Cu" signal "GND5")
		(28 "In13.Cu" signal "IN5")
		(30 "In14.Cu" signal "GND6")
		(32 "In15.Cu" signal "IN6")
		(34 "In16.Cu" signal "GND7")
		(2 "B.Cu" signal "BOTTOM")
		(9 "F.Adhes" user "F.Adhesive")
		(11 "B.Adhes" user "B.Adhesive")
		(13 "F.Paste" user "Package Geometry/Pastemask Top")
		(15 "B.Paste" user "Package Geometry/Pastemask Bottom")
		(5 "F.SilkS" user "Ref Des/Silkscreen Top")
		(7 "B.SilkS" user "Ref Des/Silkscreen Bottom")
		(1 "F.Mask" user "Board Geometry/Soldermask Top")
		(3 "B.Mask" user "Board Geometry/Soldermask Bottom")
		(17 "Dwgs.User" user "User.Drawings")
		(19 "Cmts.User" user "User.Comments")
		(21 "Eco1.User" user "User.Eco1")
		(23 "Eco2.User" user "User.Eco2")
		(25 "Edge.Cuts" user "Board Geometry/Outline")
		(27 "Margin" user)
		(31 "F.CrtYd" user "Package Geometry/Place Bound Top")
		(29 "B.CrtYd" user "Package Geometry/Place Bound Bottom")
		(35 "F.Fab" user "Ref Des/Assembly Top")
		(33 "B.Fab" user "Ref Des/Assembly Bottom")
	)
	(footprint ""
		(layer "B.Cu")
		(at 162.618928 -390.560052 90)
		(property "Reference" "C424"
			(at 0 0 90)
			(layer "B.SilkS")
			(hide yes)
			(effects
				(font
					(size 1.27 1.27)
				)
				(justify mirror)
			)
		)
		(property "Value" ""
			(at 0 0 90)
			(layer "B.Fab")
			(effects
				(font
					(size 1.27 1.27)
				)
				(justify mirror)
			)
		)
		(duplicate_pad_numbers_are_jumpers no)
		(fp_line
			(start 0.7874 -0.4064)
			(end -0.7874 -0.4064)
			(stroke
				(width 0.1524)
				(type default)
			)
			(layer "B.SilkS")
		)
		(fp_line
			(start -0.7874 -0.4064)
			(end -0.7874 0.4064)
			(stroke
				(width 0.1524)
				(type default)
			)
			(layer "B.SilkS")
		)
		(fp_line
			(start 0.7874 0.4064)
			(end 0.7874 -0.4064)
			(stroke
				(width 0.1524)
				(type default)
			)
			(layer "B.SilkS")
		)
		(fp_line
			(start -0.7874 0.4064)
			(end 0.7874 0.4064)
			(stroke
				(width 0.1524)
				(type default)
			)
			(layer "B.SilkS")
		)
		(fp_line
			(start 0.67945 -0.305054)
			(end 0.12065 -0.305054)
			(stroke
				(width 0.1)
				(type default)
			)
			(layer "B.Fab")
		)
		(fp_line
			(start 0.12065 -0.305054)
			(end 0.12065 -0.2794)
			(stroke
				(width 0.1)
				(type default)
			)
			(layer "B.Fab")
		)
		(fp_line
			(start -0.12065 -0.3048)
			(end -0.67945 -0.3048)
			(stroke
				(width 0.1)
				(type default)
			)
			(layer "B.Fab")
		)
		(fp_line
			(start -0.67945 -0.3048)
			(end -0.67945 0.3048)
			(stroke
				(width 0.1)
				(type default)
			)
			(layer "B.Fab")
		)
		(fp_line
			(start 0.12065 -0.2794)
			(end -0.12065 -0.2794)
			(stroke
				(width 0.1)
				(type default)
			)
			(layer "B.Fab")
		)
		(fp_line
			(start -0.12065 -0.2794)
			(end -0.12065 -0.3048)
			(stroke
				(width 0.1)
				(type default)
			)
			(layer "B.Fab")
		)
		(fp_line
			(start 0.12065 0.2794)
			(end 0.12065 0.3048)
			(stroke
				(width 0.1)
				(type default)
			)
			(layer "B.Fab")
		)
		(fp_line
			(start -0.120396 0.2794)
			(end 0.12065 0.2794)
			(stroke
				(width 0.1)
				(type default)
			)
			(layer "B.Fab")
		)
		(fp_line
			(start 0.67945 0.3048)
			(end 0.67945 -0.305054)
			(stroke
				(width 0.1)
				(type default)
			)
			(layer "B.Fab")
		)
		(fp_line
			(start 0.12065 0.3048)
			(end 0.67945 0.3048)
			(stroke
				(width 0.1)
				(type default)
			)
			(layer "B.Fab")
		)
		(fp_line
			(start -0.120396 0.3048)
			(end -0.120396 0.2794)
			(stroke
				(width 0.1)
				(type default)
			)
			(layer "B.Fab")
		)
		(fp_line
			(start -0.67945 0.3048)
			(end -0.120396 0.3048)
			(stroke
				(width 0.1)
				(type default)
			)
			(layer "B.Fab")
		)
		(pad "1" smd circle
			(at 0.40005 0 270)
			(size 0 0)
			(layers "B.Cu" "B.Mask" "B.Paste")
			(net "P0V9_CPU1_RT2_2A")
		)
		(pad "2" smd circle
			(at -0.40005 0 270)
			(size 0 0)
			(layers "B.Cu" "B.Mask" "B.Paste")
			(net "GND")
		)
	)
	(footprint ""
		(layer "B.Cu")
		(at 121.691146 -390.560052 90)
		(property "Reference" "C489"
			(at 0 0 90)
			(layer "B.SilkS")
			(hide yes)
			(effects
				(font
					(size 1.27 1.27)
				)
				(justify mirror)
			)
		)
		(property "Value" ""
			(at 0 0 90)
			(layer "B.Fab")
			(effects
				(font
					(size 1.27 1.27)
				)
				(justify mirror)
			)
		)
		(duplicate_pad_numbers_are_jumpers no)
		(fp_line
			(start 0.7874 -0.4064)
			(end -0.7874 -0.4064)
			(stroke
				(width 0.1524)
				(type default)
			)
			(layer "B.SilkS")
		)
		(fp_line
			(start -0.7874 -0.4064)
			(end -0.7874 0.4064)
			(stroke
				(width 0.1524)
				(type default)
			)
			(layer "B.SilkS")
		)
		(fp_line
			(start 0.7874 0.4064)
			(end 0.7874 -0.4064)
			(stroke
				(width 0.1524)
				(type default)
			)
			(layer "B.SilkS")
		)
		(fp_line
			(start -0.7874 0.4064)
			(end 0.7874 0.4064)
			(stroke
				(width 0.1524)
				(type default)
			)
			(layer "B.SilkS")
		)
		(fp_line
			(start 0.67945 -0.305054)
			(end 0.12065 -0.305054)
			(stroke
				(width 0.1)
				(type default)
			)
			(layer "B.Fab")
		)
		(fp_line
			(start 0.12065 -0.305054)
			(end 0.12065 -0.2794)
			(stroke
				(width 0.1)
				(type default)
			)
			(layer "B.Fab")
		)
		(fp_line
			(start -0.12065 -0.3048)
			(end -0.67945 -0.3048)
			(stroke
				(width 0.1)
				(type default)
			)
			(layer "B.Fab")
		)
		(fp_line
			(start -0.67945 -0.3048)
			(end -0.67945 0.3048)
			(stroke
				(width 0.1)
				(type default)
			)
			(layer "B.Fab")
		)
		(fp_line
			(start 0.12065 -0.2794)
			(end -0.12065 -0.2794)
			(stroke
				(width 0.1)
				(type default)
			)
			(layer "B.Fab")
		)
		(fp_line
			(start -0.12065 -0.2794)
			(end -0.12065 -0.3048)
			(stroke
				(width 0.1)
				(type default)
			)
			(layer "B.Fab")
		)
		(fp_line
			(start 0.12065 0.2794)
			(end 0.12065 0.3048)
			(stroke
				(width 0.1)
				(type default)
			)
			(layer "B.Fab")
		)
		(fp_line
			(start -0.120396 0.2794)
			(end 0.12065 0.2794)
			(stroke
				(width 0.1)
				(type default)
			)
			(layer "B.Fab")
		)
		(fp_line
			(start 0.67945 0.3048)
			(end 0.67945 -0.305054)
			(stroke
				(width 0.1)
				(type default)
			)
			(layer "B.Fab")
		)
		(fp_line
			(start 0.12065 0.3048)
			(end 0.67945 0.3048)
			(stroke
				(width 0.1)
				(type default)
			)
			(layer "B.Fab")
		)
		(fp_line
			(start -0.120396 0.3048)
			(end -0.120396 0.2794)
			(stroke
				(width 0.1)
				(type default)
			)
			(layer "B.Fab")
		)
		(fp_line
			(start -0.67945 0.3048)
			(end -0.120396 0.3048)
			(stroke
				(width 0.1)
				(type default)
			)
			(layer "B.Fab")
		)
		(pad "1" smd circle
			(at 0.40005 0 270)
			(size 0 0)
			(layers "B.Cu" "B.Mask" "B.Paste")
			(net "P0V9_CPU1_RT_2D")
		)
		(pad "2" smd circle
			(at -0.40005 0 270)
			(size 0 0)
			(layers "B.Cu" "B.Mask" "B.Paste")
			(net "GND")
		)
	)
	(footprint ""
		(layer "B.Cu")
		(at 52.318412 -388.011162 -90)
		(property "Reference" "C191"
			(at 0 0 90)
			(layer "B.SilkS")
			(hide yes)
			(effects
				(font
					(size 1.27 1.27)
				)
				(justify mirror)
			)
		)
		(property "Value" ""
			(at 0 0 90)
			(layer "B.Fab")
			(effects
				(font
					(size 1.27 1.27)
				)
				(justify mirror)
			)
		)
		(duplicate_pad_numbers_are_jumpers no)
		(fp_line
			(start -0.299974 0.150114)
			(end 0.299974 0.150114)
			(stroke
				(width 0.1)
				(type default)
			)
			(layer "B.Fab")
		)
		(fp_line
			(start 0.299974 0.150114)
			(end 0.299974 -0.150114)
			(stroke
				(width 0.1)
				(type default)
			)
			(layer "B.Fab")
		)
		(fp_line
			(start -0.299974 -0.150114)
			(end -0.299974 0.150114)
			(stroke
				(width 0.1)
				(type default)
			)
			(layer "B.Fab")
		)
		(fp_line
			(start 0.299974 -0.150114)
			(end -0.299974 -0.150114)
			(stroke
				(width 0.1)
				(type default)
			)
			(layer "B.Fab")
		)
		(pad "1" smd rect
			(at 0.2667 0 90)
			(size 0.3048 0.381)
			(layers "B.Cu" "B.Mask" "B.Paste")
			(net "P0V9_CPU1_RT0_2A_2D")
		)
		(pad "2" smd rect
			(at -0.2667 0 90)
			(size 0.3048 0.381)
			(layers "B.Cu" "B.Mask" "B.Paste")
			(net "GND")
		)
	)
)
